(kicad_pcb
	(version 20221018)
	(generator pcbnew)
	(general
    (thickness 1.518)
  )
	(paper "A4")
	(title_block
    (title "Kria K26 Devboard")
    (date "2024-03-26")
    (rev "1.2.5")
    (comment 1 "www.antmicro.com")
    (comment 2 "Antmicro Ltd.")
		(comment 9 "footprints 352-361 of 660")
	)
	(layers
    (0 "F.Cu" mixed)
    (1 "In1.Cu" power)
    (2 "In2.Cu" mixed)
    (3 "In3.Cu" power)
    (4 "In4.Cu" mixed)
    (5 "In5.Cu" power)
    (6 "In6.Cu" mixed)
    (31 "B.Cu" power)
    (32 "B.Adhes" user "B.Adhesive")
    (33 "F.Adhes" user "F.Adhesive")
    (34 "B.Paste" user)
    (35 "F.Paste" user)
    (36 "B.SilkS" user "B.Silkscreen")
    (37 "F.SilkS" user "F.Silkscreen")
    (38 "B.Mask" user)
    (39 "F.Mask" user)
    (40 "Dwgs.User" user "User.Drawings")
    (41 "Cmts.User" user "User.Comments")
    (42 "Eco1.User" user "User.Eco1")
    (43 "Eco2.User" user "User.Eco2")
    (44 "Edge.Cuts" user)
    (45 "Margin" user)
    (46 "B.CrtYd" user "B.Courtyard")
    (47 "F.CrtYd" user "F.Courtyard")
    (48 "B.Fab" user)
    (49 "F.Fab" user)
  )
	(footprint "kria-k26-devboard-footprints:TP_SMD_0.75mm" (layer "F.Cu")
    (at 109.3 146.5)
    (property "Author" "Antmicro")
    (property "License" "Apache-2.0")
    (property "MPN" "")
    (property "Manufacturer" "")
    (property "Sheetfile" "reset.kicad_sch")
    (property "Sheetname" "Reset logic")
    (property "ki_description" "Test Point 0.75mm")
    (attr exclude_from_pos_files)
    (fp_text reference "TP17" (at 7.33 0.86 90) (layer "F.SilkS")
        (effects (font (size 0.7 0.7) (thickness 0.15)) (justify left bottom))
    )
    (fp_text value "TP_0.75mm_SMD" (at 0 1.2) (layer "F.Fab") hide
        (effects (font (size 0.7 0.7) (thickness 0.15)) (justify left bottom))
    )
    (fp_text user "License: Apache-2.0" (at -0.4 5.101) (layer "F.Fab") hide
        (effects (font (size 0.7 0.7) (thickness 0.15)) (justify left bottom))
    )
    (fp_text user "${REFERENCE}" (at -0.4 2.7) (layer "F.Fab") hide
        (effects (font (size 0.7 0.7) (thickness 0.15)) (justify left bottom))
    )
    (fp_text user "Author: Antmicro" (at -0.4 3.901) (layer "F.Fab") hide
        (effects (font (size 0.7 0.7) (thickness 0.15)) (justify left bottom))
    )
    (pad "1" smd circle (at 0 0) (size 0.75 0.75) (layers "F.Cu" "F.Mask")
      (net 177 "/Reset logic/~{SD_CARD_RESET}") (pinfunction "1") (pintype "passive"))
  )
	(footprint "kria-k26-devboard-footprints:TP_SMD_0.75mm" (layer "F.Cu")
    (at 110.3 146.5)
    (property "Author" "Antmicro")
    (property "License" "Apache-2.0")
    (property "MPN" "")
    (property "Manufacturer" "")
    (property "Sheetfile" "reset.kicad_sch")
    (property "Sheetname" "Reset logic")
    (property "ki_description" "Test Point 0.75mm")
    (attr exclude_from_pos_files)
    (fp_text reference "TP18" (at 7.33 0.86 90) (layer "F.SilkS")
        (effects (font (size 0.7 0.7) (thickness 0.15)) (justify left bottom))
    )
    (fp_text value "TP_0.75mm_SMD" (at 0 1.2) (layer "F.Fab") hide
        (effects (font (size 0.7 0.7) (thickness 0.15)) (justify left bottom))
    )
    (fp_text user "${REFERENCE}" (at -0.4 2.7) (layer "F.Fab") hide
        (effects (font (size 0.7 0.7) (thickness 0.15)) (justify left bottom))
    )
    (fp_text user "Author: Antmicro" (at -0.4 3.901) (layer "F.Fab") hide
        (effects (font (size 0.7 0.7) (thickness 0.15)) (justify left bottom))
    )
    (fp_text user "License: Apache-2.0" (at -0.4 5.101) (layer "F.Fab") hide
        (effects (font (size 0.7 0.7) (thickness 0.15)) (justify left bottom))
    )
    (pad "1" smd circle (at 0 0) (size 0.75 0.75) (layers "F.Cu" "F.Mask")
      (net 178 "/Reset logic/~{USB_PHY_RESET}") (pinfunction "1") (pintype "passive"))
  )
	(footprint "kria-k26-devboard-footprints:TP_SMD_0.75mm" (layer "F.Cu")
    (at 112.3 146.5)
    (property "Author" "Antmicro")
    (property "License" "Apache-2.0")
    (property "MPN" "")
    (property "Manufacturer" "")
    (property "Sheetfile" "reset.kicad_sch")
    (property "Sheetname" "Reset logic")
    (property "ki_description" "Test Point 0.75mm")
    (attr exclude_from_pos_files)
    (fp_text reference "TP20" (at 7.33 0.86 90) (layer "F.SilkS")
        (effects (font (size 0.7 0.7) (thickness 0.15)) (justify left bottom))
    )
    (fp_text value "TP_0.75mm_SMD" (at 0 1.2) (layer "F.Fab") hide
        (effects (font (size 0.7 0.7) (thickness 0.15)) (justify left bottom))
    )
    (fp_text user "Author: Antmicro" (at -0.4 3.901) (layer "F.Fab") hide
        (effects (font (size 0.7 0.7) (thickness 0.15)) (justify left bottom))
    )
    (fp_text user "License: Apache-2.0" (at -0.4 5.101) (layer "F.Fab") hide
        (effects (font (size 0.7 0.7) (thickness 0.15)) (justify left bottom))
    )
    (fp_text user "${REFERENCE}" (at -0.4 2.7) (layer "F.Fab") hide
        (effects (font (size 0.7 0.7) (thickness 0.15)) (justify left bottom))
    )
    (pad "1" smd circle (at 0 0) (size 0.75 0.75) (layers "F.Cu" "F.Mask")
      (net 176 "/Ethernet/~{ETH_RESET}") (pinfunction "1") (pintype "passive"))
  )
	(footprint "kria-k26-devboard-footprints:TP_SMD_0.75mm" (layer "F.Cu")
    (at 115.3 146.5)
    (property "Author" "Antmicro")
    (property "License" "Apache-2.0")
    (property "MPN" "")
    (property "Manufacturer" "")
    (property "Sheetfile" "reset.kicad_sch")
    (property "Sheetname" "Reset logic")
    (property "ki_description" "Test Point 0.75mm")
    (attr exclude_from_pos_files)
    (fp_text reference "TP21" (at 7.33 0.86 90) (layer "F.SilkS")
        (effects (font (size 0.7 0.7) (thickness 0.15)) (justify left bottom))
    )
    (fp_text value "TP_0.75mm_SMD" (at 0 1.2) (layer "F.Fab") hide
        (effects (font (size 0.7 0.7) (thickness 0.15)) (justify left bottom))
    )
    (fp_text user "Author: Antmicro" (at -0.4 3.901) (layer "F.Fab") hide
        (effects (font (size 0.7 0.7) (thickness 0.15)) (justify left bottom))
    )
    (fp_text user "License: Apache-2.0" (at -0.4 5.101) (layer "F.Fab") hide
        (effects (font (size 0.7 0.7) (thickness 0.15)) (justify left bottom))
    )
    (fp_text user "${REFERENCE}" (at -0.4 2.7) (layer "F.Fab") hide
        (effects (font (size 0.7 0.7) (thickness 0.15)) (justify left bottom))
    )
    (pad "1" smd circle (at 0 0) (size 0.75 0.75) (layers "F.Cu" "F.Mask")
      (net 1 "GND") (pinfunction "1") (pintype "passive"))
  )
	(footprint "kria-k26-devboard-footprints:TP_SMD_0.75mm" (layer "F.Cu")
    (at 113.3 146.49)
    (property "Author" "Antmicro")
    (property "License" "Apache-2.0")
    (property "MPN" "")
    (property "Manufacturer" "")
    (property "Sheetfile" "reset.kicad_sch")
    (property "Sheetname" "Reset logic")
    (property "ki_description" "Test Point 0.75mm")
    (attr exclude_from_pos_files)
    (fp_text reference "TP22" (at 7.33 0.86 90) (layer "F.SilkS")
        (effects (font (size 0.7 0.7) (thickness 0.15)) (justify left bottom))
    )
    (fp_text value "TP_0.75mm_SMD" (at 0 1.2) (layer "F.Fab") hide
        (effects (font (size 0.7 0.7) (thickness 0.15)) (justify left bottom))
    )
    (fp_text user "${REFERENCE}" (at -0.4 2.7) (layer "F.Fab") hide
        (effects (font (size 0.7 0.7) (thickness 0.15)) (justify left bottom))
    )
    (fp_text user "License: Apache-2.0" (at -0.4 5.101) (layer "F.Fab") hide
        (effects (font (size 0.7 0.7) (thickness 0.15)) (justify left bottom))
    )
    (fp_text user "Author: Antmicro" (at -0.4 3.901) (layer "F.Fab") hide
        (effects (font (size 0.7 0.7) (thickness 0.15)) (justify left bottom))
    )
    (pad "1" smd circle (at 0 0) (size 0.75 0.75) (layers "F.Cu" "F.Mask")
      (net 198 "/Camera interface/CAM0_RST") (pinfunction "1") (pintype "passive"))
  )
	(footprint "kria-k26-devboard-footprints:TP_SMD_0.75mm" (layer "F.Cu")
    (at 114.3 146.5)
    (property "Author" "Antmicro")
    (property "License" "Apache-2.0")
    (property "MPN" "")
    (property "Manufacturer" "")
    (property "Sheetfile" "reset.kicad_sch")
    (property "Sheetname" "Reset logic")
    (property "ki_description" "Test Point 0.75mm")
    (attr exclude_from_pos_files)
    (fp_text reference "TP23" (at 7.33 0.86 90) (layer "F.SilkS")
        (effects (font (size 0.7 0.7) (thickness 0.15)) (justify left bottom))
    )
    (fp_text value "TP_0.75mm_SMD" (at 0 1.2) (layer "F.Fab") hide
        (effects (font (size 0.7 0.7) (thickness 0.15)) (justify left bottom))
    )
    (fp_text user "License: Apache-2.0" (at -0.4 5.101) (layer "F.Fab") hide
        (effects (font (size 0.7 0.7) (thickness 0.15)) (justify left bottom))
    )
    (fp_text user "Author: Antmicro" (at -0.4 3.901) (layer "F.Fab") hide
        (effects (font (size 0.7 0.7) (thickness 0.15)) (justify left bottom))
    )
    (fp_text user "${REFERENCE}" (at -0.4 2.7) (layer "F.Fab") hide
        (effects (font (size 0.7 0.7) (thickness 0.15)) (justify left bottom))
    )
    (pad "1" smd circle (at 0 0) (size 0.75 0.75) (layers "F.Cu" "F.Mask")
      (net 221 "/PCIE M2 key E /~{M2_PERST}") (pinfunction "1") (pintype "passive"))
  )
	(footprint "kria-k26-devboard-footprints:USON-10_2.5x1mm_P0.5mm" (layer "F.Cu")
    (at 86 68.75 90)
    (descr "USON-10 2.5x1mm_ Pitch 0.5mm")
    (tags "USON-10 2.5x1mm Pitch 0.5mm")
    (property "Author" "Antmicro")
    (property "License" "Apache-2.0")
    (property "MPN" "TPD4E05U06QDQARQ1")
    (property "Manufacturer" "Texas Instruments")
    (property "Sheetfile" "dp.kicad_sch")
    (property "Sheetname" "Display Port")
    (property "ki_description" "ESD protection")
    (property "ki_keywords" "SMT, DIODE, IC, TVS, ESD")
    (attr smd)
    (fp_text reference "U3" (at 0.018 -1.7 90) (layer "F.SilkS")
        (effects (font (size 0.7 0.7) (thickness 0.15)) (justify left bottom))
    )
    (fp_text value "TPD4E05U06QDQARQ1" (at 0.018 2.499 90) (layer "F.Fab")
        (effects (font (size 0.7 0.7) (thickness 0.15)) (justify left bottom))
    )
    (fp_text user "${REFERENCE}" (at -0.802 4.498 90) (layer "F.Fab") hide
        (effects (font (size 0.7 0.7) (thickness 0.15)) (justify left bottom))
    )
    (fp_text user "License: Apache-2.0" (at -0.802 6.9 90) (layer "F.Fab") hide
        (effects (font (size 0.7 0.7) (thickness 0.15)) (justify left bottom))
    )
    (fp_text user "Author: Antmicro" (at -0.802 5.7 90) (layer "F.Fab") hide
        (effects (font (size 0.7 0.7) (thickness 0.15)) (justify left bottom))
    )
    (fp_line (start 0.498 -1.401) (end -0.5 -1.401)
      (stroke (width 0.15) (type solid)) (layer "F.SilkS"))
    (fp_line (start 0.498 1.398) (end -0.5 1.398)
      (stroke (width 0.15) (type solid)) (layer "F.SilkS"))
    (fp_circle (center -0.68 -1.27) (end -0.63 -1.27)
      (stroke (width 0.15) (type solid)) (fill solid) (layer "F.SilkS"))
    (fp_rect (start -0.8 -1.5) (end 0.8 1.499)
      (stroke (width 0.05) (type solid)) (fill none) (layer "F.CrtYd"))
    (fp_line (start -0.5 -1) (end -0.5 1.249)
      (stroke (width 0.15) (type solid)) (layer "F.Fab"))
    (fp_line (start -0.5 1.249) (end 0.498 1.249)
      (stroke (width 0.15) (type solid)) (layer "F.Fab"))
    (fp_line (start -0.25 -1.25) (end -0.5 -1)
      (stroke (width 0.15) (type solid)) (layer "F.Fab"))
    (fp_line (start 0.498 -1.25) (end -0.25 -1.25)
      (stroke (width 0.15) (type solid)) (layer "F.Fab"))
    (fp_line (start 0.498 -1.25) (end 0.498 1.249)
      (stroke (width 0.15) (type solid)) (layer "F.Fab"))
    (pad "1" smd roundrect (at -0.387 -1) (size 0.25 0.55) (layers "F.Cu" "F.Paste" "F.Mask") (roundrect_rratio 0.25)
      (net 93 "/Display Port/GTR_DP1_M2C_C_P") (pintype "passive"))
    (pad "2" smd roundrect (at -0.387 -0.5) (size 0.25 0.55) (layers "F.Cu" "F.Paste" "F.Mask") (roundrect_rratio 0.25)
      (net 95 "/Display Port/GTR_DP1_M2C_C_N") (pintype "passive"))
    (pad "3" smd roundrect (at -0.387 0) (size 0.4 0.55) (layers "F.Cu" "F.Paste" "F.Mask") (roundrect_rratio 0.25)
      (net 1 "GND") (pintype "power_in"))
    (pad "4" smd roundrect (at -0.387 0.498) (size 0.25 0.55) (layers "F.Cu" "F.Paste" "F.Mask") (roundrect_rratio 0.25)
      (net 101 "/Display Port/GTR_DP0_M2C_C_P") (pintype "passive"))
    (pad "5" smd roundrect (at -0.387 0.998) (size 0.25 0.55) (layers "F.Cu" "F.Paste" "F.Mask") (roundrect_rratio 0.25)
      (net 103 "/Display Port/GTR_DP0_M2C_C_N") (pintype "passive"))
    (pad "6" smd roundrect (at 0.385 0.998) (size 0.25 0.55) (layers "F.Cu" "F.Paste" "F.Mask") (roundrect_rratio 0.25)
      (net 103 "/Display Port/GTR_DP0_M2C_C_N") (pintype "passive"))
    (pad "7" smd roundrect (at 0.385 0.498) (size 0.25 0.55) (layers "F.Cu" "F.Paste" "F.Mask") (roundrect_rratio 0.25)
      (net 101 "/Display Port/GTR_DP0_M2C_C_P") (pintype "passive"))
    (pad "8" smd roundrect (at 0.385 0) (size 0.4 0.55) (layers "F.Cu" "F.Paste" "F.Mask") (roundrect_rratio 0.25)
      (net 1 "GND") (pintype "passive"))
    (pad "9" smd roundrect (at 0.385 -0.5) (size 0.25 0.55) (layers "F.Cu" "F.Paste" "F.Mask") (roundrect_rratio 0.25)
      (net 95 "/Display Port/GTR_DP1_M2C_C_N") (pintype "passive"))
    (pad "10" smd roundrect (at 0.385 -1) (size 0.25 0.55) (layers "F.Cu" "F.Paste" "F.Mask") (roundrect_rratio 0.25)
      (net 93 "/Display Port/GTR_DP1_M2C_C_P") (pintype "passive"))
  )
	(footprint "kria-k26-devboard-footprints:R_0402_1005Metric" (layer "F.Cu")
    (at 114.326942 87.874861)
    (descr "Resistor SMD 0402")
    (tags "resistor SMD 0402")
    (property "Author" "Antmicro")
    (property "License" "Apache-2.0")
    (property "MPN" "CR0402-FX-2003GLF")
    (property "Manufacturer" "Bourns")
    (property "Sheetfile" "usb.kicad_sch")
    (property "Sheetname" "USB")
    (property "Tolerance" "1%")
    (property "Val" "200k")
    (property "ki_description" "200k resistor in 0402 package with 1% tolerance")
    (attr smd)
    (fp_text reference "R42" (at -3.156942 0.655139) (layer "F.SilkS")
        (effects (font (size 0.7 0.7) (thickness 0.15)) (justify left bottom))
    )
    (fp_text value "R_200k_0402" (at 0 1.4) (layer "F.Fab") hide
        (effects (font (size 0.7 0.7) (thickness 0.15)) (justify left bottom))
    )
    (fp_text user "License: Apache-2.0" (at -0.95 5.169) (layer "F.Fab") hide
        (effects (font (size 0.7 0.7) (thickness 0.15)) (justify left bottom))
    )
    (fp_text user "${REFERENCE}" (at -0.95 3.168) (layer "F.Fab") hide
        (effects (font (size 0.7 0.7) (thickness 0.15)) (justify left bottom))
    )
    (fp_text user "Author: Antmicro" (at -0.95 4.169) (layer "F.Fab") hide
        (effects (font (size 0.7 0.7) (thickness 0.15)) (justify left bottom))
    )
    (fp_rect (start -0.93 -0.47) (end 0.93 0.47)
      (stroke (width 0.05) (type solid)) (fill none) (layer "F.CrtYd"))
    (fp_rect (start -0.5 -0.25) (end 0.5 0.25)
      (stroke (width 0.15) (type solid)) (fill none) (layer "F.Fab"))
    (pad "1" smd roundrect (at -0.485 0) (size 0.59 0.64) (layers "F.Cu" "F.Paste" "F.Mask") (roundrect_rratio 0.25)
      (net 1 "GND") (pintype "passive"))
    (pad "2" smd roundrect (at 0.485 0) (size 0.59 0.64) (layers "F.Cu" "F.Paste" "F.Mask") (roundrect_rratio 0.25)
      (net 645 "Net-(U17-SPI_D0{slash}CFG_BC_EN{slash}PF22)") (pintype "passive"))
  )
	(footprint "kria-k26-devboard-footprints:R_0402_1005Metric" (layer "F.Cu")
    (at 114.326939 86.87486)
    (descr "Resistor SMD 0402")
    (tags "resistor SMD 0402")
    (property "Author" "Antmicro")
    (property "License" "Apache-2.0")
    (property "MPN" "CR0402-FX-2003GLF")
    (property "Manufacturer" "Bourns")
    (property "Sheetfile" "usb.kicad_sch")
    (property "Sheetname" "USB")
    (property "Tolerance" "1%")
    (property "Val" "200k")
    (property "ki_description" "200k resistor in 0402 package with 1% tolerance")
    (attr smd)
    (fp_text reference "R40" (at -3.166939 0.58514) (layer "F.SilkS")
        (effects (font (size 0.7 0.7) (thickness 0.15)) (justify left bottom))
    )
    (fp_text value "R_200k_0402" (at 0 1.4) (layer "F.Fab") hide
        (effects (font (size 0.7 0.7) (thickness 0.15)) (justify left bottom))
    )
    (fp_text user "${REFERENCE}" (at -0.95 3.168) (layer "F.Fab") hide
        (effects (font (size 0.7 0.7) (thickness 0.15)) (justify left bottom))
    )
    (fp_text user "License: Apache-2.0" (at -0.95 5.169) (layer "F.Fab") hide
        (effects (font (size 0.7 0.7) (thickness 0.15)) (justify left bottom))
    )
    (fp_text user "Author: Antmicro" (at -0.95 4.169) (layer "F.Fab") hide
        (effects (font (size 0.7 0.7) (thickness 0.15)) (justify left bottom))
    )
    (fp_rect (start -0.93 -0.47) (end 0.93 0.47)
      (stroke (width 0.05) (type solid)) (fill none) (layer "F.CrtYd"))
    (fp_rect (start -0.5 -0.25) (end 0.5 0.25)
      (stroke (width 0.15) (type solid)) (fill none) (layer "F.Fab"))
    (pad "1" smd roundrect (at -0.485 0) (size 0.59 0.64) (layers "F.Cu" "F.Paste" "F.Mask") (roundrect_rratio 0.25)
      (net 1 "GND") (pintype "passive"))
    (pad "2" smd roundrect (at 0.485 0) (size 0.59 0.64) (layers "F.Cu" "F.Paste" "F.Mask") (roundrect_rratio 0.25)
      (net 643 "Net-(U17-SPI_CLK{slash}PF21)") (pintype "passive"))
  )
	(footprint "kria-k26-devboard-footprints:R_0402_1005Metric" (layer "F.Cu")
    (at 114.311942 88.874862)
    (descr "Resistor SMD 0402")
    (tags "resistor SMD 0402")
    (property "Author" "Antmicro")
    (property "License" "Apache-2.0")
    (property "MPN" "CR0402-FX-2003GLF")
    (property "Manufacturer" "Bourns")
    (property "Sheetfile" "usb.kicad_sch")
    (property "Sheetname" "USB")
    (property "Tolerance" "1%")
    (property "Val" "200k")
    (property "ki_description" "200k resistor in 0402 package with 1% tolerance")
    (attr smd)
    (fp_text reference "R44" (at -3.156942 0.655139) (layer "F.SilkS")
        (effects (font (size 0.7 0.7) (thickness 0.15)) (justify left bottom))
    )
    (fp_text value "R_200k_0402" (at 0 1.4) (layer "F.Fab") hide
        (effects (font (size 0.7 0.7) (thickness 0.15)) (justify left bottom))
    )
    (fp_text user "License: Apache-2.0" (at -0.95 5.169) (layer "F.Fab") hide
        (effects (font (size 0.7 0.7) (thickness 0.15)) (justify left bottom))
    )
    (fp_text user "Author: Antmicro" (at -0.95 4.169) (layer "F.Fab") hide
        (effects (font (size 0.7 0.7) (thickness 0.15)) (justify left bottom))
    )
    (fp_text user "${REFERENCE}" (at -0.95 3.168) (layer "F.Fab") hide
        (effects (font (size 0.7 0.7) (thickness 0.15)) (justify left bottom))
    )
    (fp_rect (start -0.93 -0.47) (end 0.93 0.47)
      (stroke (width 0.05) (type solid)) (fill none) (layer "F.CrtYd"))
    (fp_rect (start -0.5 -0.25) (end 0.5 0.25)
      (stroke (width 0.15) (type solid)) (fill none) (layer "F.Fab"))
    (pad "1" smd roundrect (at -0.485 0) (size 0.59 0.64) (layers "F.Cu" "F.Paste" "F.Mask") (roundrect_rratio 0.25)
      (net 1 "GND") (pintype "passive"))
    (pad "2" smd roundrect (at 0.485 0) (size 0.59 0.64) (layers "F.Cu" "F.Paste" "F.Mask") (roundrect_rratio 0.25)
      (net 647 "Net-(U17-SPI_D2{slash}PF24)") (pintype "passive"))
  )
)
